(kicad_pcb
	(version 20241229)
	(generator "pcbnew")
	(generator_version "9.0")
	(general
		(thickness 1.62)
		(legacy_teardrops no)
	)
	(paper "A3")
	(title_block
		(title "COM Express 7 Baseboard")
		(date "2025-02-04")
		(rev "1.1.2")
		(company "Antmicro Ltd")
		(comment 1 "www.antmicro.com")
		(comment 9 "footprints 407-411 of 802")
	)
	(layers
		(0 "F.Cu" signal)
		(4 "In1.Cu" signal)
		(6 "In2.Cu" signal)
		(8 "In3.Cu" signal)
		(10 "In4.Cu" signal)
		(12 "In5.Cu" signal)
		(14 "In6.Cu" signal)
		(2 "B.Cu" signal)
		(9 "F.Adhes" user "F.Adhesive")
		(11 "B.Adhes" user "B.Adhesive")
		(13 "F.Paste" user)
		(15 "B.Paste" user)
		(5 "F.SilkS" user "F.Silkscreen")
		(7 "B.SilkS" user "B.Silkscreen")
		(1 "F.Mask" user)
		(3 "B.Mask" user)
		(17 "Dwgs.User" user "User.Drawings")
		(19 "Cmts.User" user "User.Comments")
		(21 "Eco1.User" user "User.Eco1")
		(23 "Eco2.User" user "User.Eco2")
		(25 "Edge.Cuts" user)
		(27 "Margin" user)
		(31 "F.CrtYd" user "F.Courtyard")
		(29 "B.CrtYd" user "B.Courtyard")
		(35 "F.Fab" user)
		(33 "B.Fab" user)
	)
	(footprint "antmicro-footprints:Choke_0805_2012Metric"
		(layer "F.Cu")
		(at 127.25 113.31 180)
		(property "Reference" "T1"
			(at 1.6 -1.85 0)
			(unlocked yes)
			(layer "F.SilkS")
			(effects
				(font
					(size 0.7 0.7)
					(thickness 0.15)
				)
				(justify left bottom)
			)
		)
		(property "Value" "Choke_SRF2012A-801Y"
			(at 0 -7 180)
			(unlocked yes)
			(layer "F.Fab")
			(effects
				(font
					(size 0.7 0.7)
					(thickness 0.15)
				)
				(justify left bottom)
			)
		)
		(property "Datasheet" "https://www.bourns.com/docs/product-datasheets/srf2012a-801y.pdf"
			(at 0 0 180)
			(layer "F.Fab")
			(hide yes)
			(effects
				(font
					(size 1.27 1.27)
					(thickness 0.15)
				)
			)
		)
		(property "Author" "Antmicro"
			(at 254.5 226.62 0)
			(layer "F.Fab")
			(hide yes)
			(effects
				(font
					(size 1 1)
					(thickness 0.15)
				)
			)
		)
		(property "IMax" "0.3 A"
			(at 254.5 226.62 0)
			(layer "F.Fab")
			(hide yes)
			(effects
				(font
					(size 1 1)
					(thickness 0.15)
				)
			)
		)
		(property "License" "Apache-2.0"
			(at 254.5 226.62 0)
			(layer "F.Fab")
			(hide yes)
			(effects
				(font
					(size 1 1)
					(thickness 0.15)
				)
			)
		)
		(property "MPN" "SRF2012A-801Y"
			(at 254.5 226.62 0)
			(layer "F.Fab")
			(hide yes)
			(effects
				(font
					(size 1 1)
					(thickness 0.15)
				)
			)
		)
		(property "Manufacturer" "Bourns"
			(at 254.5 226.62 0)
			(layer "F.Fab")
			(hide yes)
			(effects
				(font
					(size 1 1)
					(thickness 0.15)
				)
			)
		)
		(property "Public" "False"
			(at 254.5 226.62 0)
			(layer "F.Fab")
			(hide yes)
			(effects
				(font
					(size 1 1)
					(thickness 0.15)
				)
			)
		)
		(property ki_fp_filters "IND_ACM9070_TDK")
		(sheetname "2xUSB3.0+RJ45")
		(sheetfile "usb3+rj45.kicad_sch")
		(attr smd)
		(fp_rect
			(start -1.5 -0.9)
			(end 1.5 0.9)
			(stroke
				(width 0.05)
				(type solid)
			)
			(fill no)
			(layer "F.CrtYd")
		)
		(pad "1" smd roundrect
			(at -0.96 -0.46 180)
			(size 0.675 0.475)
			(layers "F.Cu" "F.Mask" "F.Paste")
			(roundrect_rratio 0.25)
			(net 689 "/2xUSB3.0+RJ45/DA_FL+")
			(pinfunction "1")
			(pintype "passive")
			(teardrops
				(best_length_ratio 0.2)
				(max_length 1)
				(best_width_ratio 0.9)
				(max_width 2)
				(curved_edges yes)
				(filter_ratio 0.9)
				(enabled yes)
				(allow_two_segments yes)
				(prefer_zone_connections yes)
			)
		)
		(pad "2" smd roundrect
			(at 0.96 -0.46 180)
			(size 0.675 0.475)
			(layers "F.Cu" "F.Mask" "F.Paste")
			(roundrect_rratio 0.25)
			(net 146 "/2xUSB3.0+RJ45/DA+")
			(pinfunction "2")
			(pintype "passive")
			(teardrops
				(best_length_ratio 0.2)
				(max_length 1)
				(best_width_ratio 0.9)
				(max_width 2)
				(curved_edges yes)
				(filter_ratio 0.9)
				(enabled yes)
				(allow_two_segments yes)
				(prefer_zone_connections yes)
			)
		)
		(pad "3" smd roundrect
			(at 0.96 0.46 180)
			(size 0.675 0.475)
			(layers "F.Cu" "F.Mask" "F.Paste")
			(roundrect_rratio 0.25)
			(net 147 "/2xUSB3.0+RJ45/DA-")
			(pinfunction "3")
			(pintype "passive")
			(teardrops
				(best_length_ratio 0.2)
				(max_length 1)
				(best_width_ratio 0.9)
				(max_width 2)
				(curved_edges yes)
				(filter_ratio 0.9)
				(enabled yes)
				(allow_two_segments yes)
				(prefer_zone_connections yes)
			)
		)
		(pad "4" smd roundrect
			(at -0.96 0.46 180)
			(size 0.675 0.475)
			(layers "F.Cu" "F.Mask" "F.Paste")
			(roundrect_rratio 0.25)
			(net 690 "/2xUSB3.0+RJ45/DA_FL-")
			(pinfunction "4")
			(pintype "passive")
			(teardrops
				(best_length_ratio 0.2)
				(max_length 1)
				(best_width_ratio 0.9)
				(max_width 2)
				(curved_edges yes)
				(filter_ratio 0.9)
				(enabled yes)
				(allow_two_segments yes)
				(prefer_zone_connections yes)
			)
		)
	)
	(footprint "antmicro-footprints:R_0402_1005Metric"
		(layer "F.Cu")
		(at 212.59 132.26)
		(descr "Resistor SMD 0402")
		(tags "resistor SMD 0402")
		(property "Reference" "R314"
			(at -3.64 0.37 0)
			(layer "F.SilkS")
			(effects
				(font
					(size 0.7 0.7)
					(thickness 0.15)
				)
				(justify left bottom)
			)
		)
		(property "Value" "R_0R_0402"
			(at -1.011843 1.772047 0)
			(layer "F.Fab")
			(effects
				(font
					(size 0.7 0.7)
					(thickness 0.15)
				)
				(justify left bottom)
			)
		)
		(property "Datasheet" "https://industrial.panasonic.com/cdbs/www-data/pdf/RDA0000/AOA0000C301.pdf"
			(at 0 0 0)
			(layer "F.Fab")
			(hide yes)
			(effects
				(font
					(size 1.27 1.27)
					(thickness 0.15)
				)
			)
		)
		(property "Author" "Antmicro"
			(at 0 0 0)
			(layer "F.Fab")
			(hide yes)
			(effects
				(font
					(size 1 1)
					(thickness 0.15)
				)
			)
		)
		(property "Current" "1A"
			(at 0 0 0)
			(layer "F.Fab")
			(hide yes)
			(effects
				(font
					(size 1 1)
					(thickness 0.15)
				)
			)
		)
		(property "License" "Apache-2.0"
			(at 0 0 0)
			(layer "F.Fab")
			(hide yes)
			(effects
				(font
					(size 1 1)
					(thickness 0.15)
				)
			)
		)
		(property "MPN" "ERJ2GE0R00X"
			(at 0 0 0)
			(layer "F.Fab")
			(hide yes)
			(effects
				(font
					(size 1 1)
					(thickness 0.15)
				)
			)
		)
		(property "Manufacturer" "Panasonic"
			(at 0 0 0)
			(layer "F.Fab")
			(hide yes)
			(effects
				(font
					(size 1 1)
					(thickness 0.15)
				)
			)
		)
		(property "Public" "False"
			(at 0 0 0)
			(layer "F.Fab")
			(hide yes)
			(effects
				(font
					(size 1 1)
					(thickness 0.15)
				)
			)
		)
		(property "Tolerance" ""
			(at 0 0 0)
			(layer "F.Fab")
			(hide yes)
			(effects
				(font
					(size 1 1)
					(thickness 0.15)
				)
			)
		)
		(property "Val" "0R"
			(at 0 0 0)
			(layer "F.Fab")
			(hide yes)
			(effects
				(font
					(size 1 1)
					(thickness 0.15)
				)
			)
		)
		(sheetname "PCIe misc")
		(sheetfile "pcie_misc.kicad_sch")
		(attr smd dnp)
		(fp_rect
			(start -0.925 -0.47)
			(end 0.925 0.47)
			(stroke
				(width 0.05)
				(type default)
			)
			(fill no)
			(layer "F.CrtYd")
		)
		(fp_rect
			(start -0.5 -0.25)
			(end 0.5 0.25)
			(stroke
				(width 0.15)
				(type solid)
			)
			(fill no)
			(layer "F.Fab")
		)
		(pad "1" smd roundrect
			(at -0.48 0)
			(size 0.59 0.64)
			(layers "F.Cu" "F.Mask" "F.Paste")
			(roundrect_rratio 0.25)
			(net 945 "/GPIO expander/GPIOEX5")
			(pintype "passive")
			(teardrops
				(best_length_ratio 0.2)
				(max_length 1)
				(best_width_ratio 0.9)
				(max_width 2)
				(curved_edges yes)
				(filter_ratio 0.9)
				(enabled yes)
				(allow_two_segments yes)
				(prefer_zone_connections yes)
			)
		)
		(pad "2" smd roundrect
			(at 0.48 0)
			(size 0.59 0.64)
			(layers "F.Cu" "F.Mask" "F.Paste")
			(roundrect_rratio 0.25)
			(net 603 "Net-(U37-~{OE1})")
			(pintype "passive")
			(teardrops
				(best_length_ratio 0.2)
				(max_length 1)
				(best_width_ratio 0.9)
				(max_width 2)
				(curved_edges yes)
				(filter_ratio 0.9)
				(enabled yes)
				(allow_two_segments yes)
				(prefer_zone_connections yes)
			)
		)
	)
	(footprint "antmicro-footprints:SC-74-6_1.5x2.9mm_P0.95mm"
		(layer "F.Cu")
		(at 256.350707 78.135)
		(tags "sc74 sc-74 sot23-6 sot457 tsop6 tsop-6")
		(property "Reference" "U25"
			(at -1.129999 2.325 0)
			(layer "F.SilkS")
			(effects
				(font
					(size 0.7 0.7)
					(thickness 0.15)
				)
				(justify left bottom)
			)
		)
		(property "Value" "74LVC1G157-Q100H_SOT457"
			(at 0.001 2.7 0)
			(layer "F.Fab")
			(effects
				(font
					(size 0.7 0.7)
					(thickness 0.15)
				)
				(justify left bottom)
			)
		)
		(property "Datasheet" "https://www.mouser.com/datasheet/2/916/74LVC1G157_Q100-1578792.pdf"
			(at 0 0 0)
			(layer "F.Fab")
			(hide yes)
			(effects
				(font
					(size 1.27 1.27)
					(thickness 0.15)
				)
			)
		)
		(property "Author" "Antmicro"
			(at 0 0 0)
			(layer "F.Fab")
			(hide yes)
			(effects
				(font
					(size 1 1)
					(thickness 0.15)
				)
			)
		)
		(property "License" "Apache-2.0"
			(at 0 0 0)
			(layer "F.Fab")
			(hide yes)
			(effects
				(font
					(size 1 1)
					(thickness 0.15)
				)
			)
		)
		(property "MPN" "74LVC1G157-Q100H"
			(at 0 0 0)
			(layer "F.Fab")
			(hide yes)
			(effects
				(font
					(size 1 1)
					(thickness 0.15)
				)
			)
		)
		(property "Manufacturer" "Nexperia"
			(at 0 0 0)
			(layer "F.Fab")
			(hide yes)
			(effects
				(font
					(size 1 1)
					(thickness 0.15)
				)
			)
		)
		(sheetname "Misc")
		(sheetfile "misc.kicad_sch")
		(attr smd)
		(fp_circle
			(center -1.11 -1.454)
			(end -1.06 -1.454)
			(stroke
				(width 0.15)
				(type solid)
			)
			(fill yes)
			(layer "F.SilkS")
		)
		(fp_rect
			(start -1.7 -1.7)
			(end 1.7 1.7)
			(stroke
				(width 0.05)
				(type solid)
			)
			(fill no)
			(layer "F.CrtYd")
		)
		(fp_line
			(start -1.269 -0.915)
			(end -1.269 1.372)
			(stroke
				(width 0.15)
				(type solid)
			)
			(layer "F.Fab")
		)
		(fp_line
			(start -1.269 1.372)
			(end -1.167 1.372)
			(stroke
				(width 0.15)
				(type solid)
			)
			(layer "F.Fab")
		)
		(fp_line
			(start -1.167 1.372)
			(end 1.22 1.372)
			(stroke
				(width 0.15)
				(type solid)
			)
			(layer "F.Fab")
		)
		(fp_line
			(start -0.76 -1.422)
			(end -1.269 -0.915)
			(stroke
				(width 0.15)
				(type solid)
			)
			(layer "F.Fab")
		)
		(fp_line
			(start 1.22 -1.422)
			(end -0.76 -1.422)
			(stroke
				(width 0.15)
				(type solid)
			)
			(layer "F.Fab")
		)
		(fp_line
			(start 1.22 1.372)
			(end 1.22 -1.422)
			(stroke
				(width 0.15)
				(type solid)
			)
			(layer "F.Fab")
		)
		(pad "1" smd roundrect
			(at -1.2 -0.95)
			(size 0.8 0.55)
			(layers "F.Cu" "F.Mask" "F.Paste")
			(roundrect_rratio 0.15)
			(net 400 "/Com Express 7 MGMT/FAN_PWM")
			(pinfunction "I1")
			(pintype "input")
			(teardrops
				(best_length_ratio 0.2)
				(max_length 1)
				(best_width_ratio 0.9)
				(max_width 2)
				(curved_edges yes)
				(filter_ratio 0.9)
				(enabled yes)
				(allow_two_segments yes)
				(prefer_zone_connections yes)
			)
		)
		(pad "2" smd roundrect
			(at -1.2 0)
			(size 0.8 0.55)
			(layers "F.Cu" "F.Mask" "F.Paste")
			(roundrect_rratio 0.15)
			(net 1 "GND")
			(pinfunction "GND")
			(pintype "power_in")
			(teardrops
				(best_length_ratio 0.2)
				(max_length 1)
				(best_width_ratio 0.9)
				(max_width 2)
				(curved_edges yes)
				(filter_ratio 0.9)
				(enabled yes)
				(allow_two_segments yes)
				(prefer_zone_connections yes)
			)
		)
		(pad "3" smd roundrect
			(at -1.2 0.95)
			(size 0.8 0.55)
			(layers "F.Cu" "F.Mask" "F.Paste")
			(roundrect_rratio 0.15)
			(net 597 "/Misc/PWM1")
			(pinfunction "I0")
			(pintype "input")
			(teardrops
				(best_length_ratio 0.2)
				(max_length 1)
				(best_width_ratio 0.9)
				(max_width 2)
				(curved_edges yes)
				(filter_ratio 0.9)
				(enabled yes)
				(allow_two_segments yes)
				(prefer_zone_connections yes)
			)
		)
		(pad "4" smd roundrect
			(at 1.2 0.95)
			(size 0.8 0.55)
			(layers "F.Cu" "F.Mask" "F.Paste")
			(roundrect_rratio 0.15)
			(net 782 "/Misc/PWM_{A3V3}")
			(pinfunction "Y")
			(pintype "output")
			(teardrops
				(best_length_ratio 0.2)
				(max_length 1)
				(best_width_ratio 0.9)
				(max_width 2)
				(curved_edges yes)
				(filter_ratio 0.9)
				(enabled yes)
				(allow_two_segments yes)
				(prefer_zone_connections yes)
			)
		)
		(pad "5" smd roundrect
			(at 1.2 0)
			(size 0.8 0.55)
			(layers "F.Cu" "F.Mask" "F.Paste")
			(roundrect_rratio 0.15)
			(net 2 "+3V3")
			(pinfunction "VCC")
			(pintype "power_in")
			(teardrops
				(best_length_ratio 0.2)
				(max_length 1)
				(best_width_ratio 0.9)
				(max_width 2)
				(curved_edges yes)
				(filter_ratio 0.9)
				(enabled yes)
				(allow_two_segments yes)
				(prefer_zone_connections yes)
			)
		)
		(pad "6" smd roundrect
			(at 1.2 -0.95)
			(size 0.8 0.55)
			(layers "F.Cu" "F.Mask" "F.Paste")
			(roundrect_rratio 0.15)
			(net 595 "/Misc/PWM_{SRCSEL}")
			(pinfunction "S")
			(pintype "input")
			(teardrops
				(best_length_ratio 0.2)
				(max_length 1)
				(best_width_ratio 0.9)
				(max_width 2)
				(curved_edges yes)
				(filter_ratio 0.9)
				(enabled yes)
				(allow_two_segments yes)
				(prefer_zone_connections yes)
			)
		)
	)
	(footprint "antmicro-footprints:C_0402_1005Metric"
		(layer "F.Cu")
		(at 245.000709 78.135 -90)
		(descr "Capacitor SMD 0402")
		(tags "capacitor SMD 0402")
		(property "Reference" "C87"
			(at 0.825 -0.469999 90)
			(layer "F.SilkS")
			(effects
				(font
					(size 0.7 0.7)
					(thickness 0.15)
				)
				(justify right bottom)
			)
		)
		(property "Value" "C_100n_0402"
			(at -1.022927 2.155213 90)
			(layer "F.Fab")
			(effects
				(font
					(size 0.7 0.7)
					(thickness 0.15)
				)
				(justify right bottom)
			)
		)
		(property "Datasheet" "https://www.murata.com/products/productdetail?partno=GRM155R61H104KE14%23"
			(at 0 0 270)
			(layer "F.Fab")
			(hide yes)
			(effects
				(font
					(size 1.27 1.27)
					(thickness 0.15)
				)
			)
		)
		(property "Author" "Antmicro"
			(at 166.865709 323.135709 0)
			(layer "F.Fab")
			(hide yes)
			(effects
				(font
					(size 1 1)
					(thickness 0.15)
				)
			)
		)
		(property "Dielectric" "X5R"
			(at 166.865709 323.135709 0)
			(layer "F.Fab")
			(hide yes)
			(effects
				(font
					(size 1 1)
					(thickness 0.15)
				)
			)
		)
		(property "License" "Apache-2.0"
			(at 166.865709 323.135709 0)
			(layer "F.Fab")
			(hide yes)
			(effects
				(font
					(size 1 1)
					(thickness 0.15)
				)
			)
		)
		(property "MPN" "GRM155R61H104KE14D"
			(at 166.865709 323.135709 0)
			(layer "F.Fab")
			(hide yes)
			(effects
				(font
					(size 1 1)
					(thickness 0.15)
				)
			)
		)
		(property "Manufacturer" "Murata"
			(at 166.865709 323.135709 0)
			(layer "F.Fab")
			(hide yes)
			(effects
				(font
					(size 1 1)
					(thickness 0.15)
				)
			)
		)
		(property "Public" "False"
			(at 166.865709 323.135709 0)
			(layer "F.Fab")
			(hide yes)
			(effects
				(font
					(size 1 1)
					(thickness 0.15)
				)
			)
		)
		(property "Val" "100n"
			(at 166.865709 323.135709 0)
			(layer "F.Fab")
			(hide yes)
			(effects
				(font
					(size 1 1)
					(thickness 0.15)
				)
			)
		)
		(property "Voltage" "50V"
			(at 166.865709 323.135709 0)
			(layer "F.Fab")
			(hide yes)
			(effects
				(font
					(size 1 1)
					(thickness 0.15)
				)
			)
		)
		(sheetname "Misc")
		(sheetfile "misc.kicad_sch")
		(attr smd)
		(fp_rect
			(start -0.925 -0.47)
			(end 0.925 0.47)
			(stroke
				(width 0.05)
				(type default)
			)
			(fill no)
			(layer "F.CrtYd")
		)
		(fp_line
			(start -0.494 0.248)
			(end -0.494 -0.25)
			(stroke
				(width 0.15)
				(type solid)
			)
			(layer "F.Fab")
		)
		(fp_line
			(start 0.504 0.248)
			(end -0.494 0.248)
			(stroke
				(width 0.15)
				(type solid)
			)
			(layer "F.Fab")
		)
		(fp_line
			(start -0.494 -0.25)
			(end 0.504 -0.25)
			(stroke
				(width 0.15)
				(type solid)
			)
			(layer "F.Fab")
		)
		(fp_line
			(start 0.504 -0.25)
			(end 0.504 0.248)
			(stroke
				(width 0.15)
				(type solid)
			)
			(layer "F.Fab")
		)
		(pad "1" smd roundrect
			(at -0.48 0 270)
			(size 0.59 0.64)
			(layers "F.Cu" "F.Mask" "F.Paste")
			(roundrect_rratio 0.25)
			(net 1 "GND")
			(pintype "passive")
			(teardrops
				(best_length_ratio 0.2)
				(max_length 1)
				(best_width_ratio 0.9)
				(max_width 2)
				(curved_edges yes)
				(filter_ratio 0.9)
				(enabled yes)
				(allow_two_segments yes)
				(prefer_zone_connections yes)
			)
		)
		(pad "2" smd roundrect
			(at 0.48 0 270)
			(size 0.59 0.64)
			(layers "F.Cu" "F.Mask" "F.Paste")
			(roundrect_rratio 0.25)
			(net 2 "+3V3")
			(pintype "passive")
			(teardrops
				(best_length_ratio 0.2)
				(max_length 1)
				(best_width_ratio 0.9)
				(max_width 2)
				(curved_edges yes)
				(filter_ratio 0.9)
				(enabled yes)
				(allow_two_segments yes)
				(prefer_zone_connections yes)
			)
		)
	)
	(footprint "antmicro-footprints:R_0402_1005Metric"
		(layer "F.Cu")
		(at 306.65 155.71 -90)
		(descr "Resistor SMD 0402")
		(tags "resistor SMD 0402")
		(property "Reference" "R164"
			(at -0.9 0.5 90)
			(layer "F.SilkS")
			(effects
				(font
					(size 0.7 0.7)
					(thickness 0.15)
				)
				(justify right bottom)
			)
		)
		(property "Value" "R_100k_0402"
			(at -1.011843 1.772047 90)
			(layer "F.Fab")
			(effects
				(font
					(size 0.7 0.7)
					(thickness 0.15)
				)
				(justify right bottom)
			)
		)
		(property "Datasheet" "https://www.bourns.com/docs/product-datasheets/cr.pdf"
			(at 0 0 270)
			(layer "F.Fab")
			(hide yes)
			(effects
				(font
					(size 1.27 1.27)
					(thickness 0.15)
				)
			)
		)
		(property "Author" "Antmicro"
			(at 150.94 462.36 0)
			(layer "F.Fab")
			(hide yes)
			(effects
				(font
					(size 1 1)
					(thickness 0.15)
				)
			)
		)
		(property "License" "Apache-2.0"
			(at 150.94 462.36 0)
			(layer "F.Fab")
			(hide yes)
			(effects
				(font
					(size 1 1)
					(thickness 0.15)
				)
			)
		)
		(property "MPN" "CR0402-FX-1003GLF"
			(at 150.94 462.36 0)
			(layer "F.Fab")
			(hide yes)
			(effects
				(font
					(size 1 1)
					(thickness 0.15)
				)
			)
		)
		(property "Manufacturer" "Bourns"
			(at 150.94 462.36 0)
			(layer "F.Fab")
			(hide yes)
			(effects
				(font
					(size 1 1)
					(thickness 0.15)
				)
			)
		)
		(property "Public" "False"
			(at 150.94 462.36 0)
			(layer "F.Fab")
			(hide yes)
			(effects
				(font
					(size 1 1)
					(thickness 0.15)
				)
			)
		)
		(property "Tolerance" "1%"
			(at 150.94 462.36 0)
			(layer "F.Fab")
			(hide yes)
			(effects
				(font
					(size 1 1)
					(thickness 0.15)
				)
			)
		)
		(property "Val" "100k"
			(at 150.94 462.36 0)
			(layer "F.Fab")
			(hide yes)
			(effects
				(font
					(size 1 1)
					(thickness 0.15)
				)
			)
		)
		(sheetname "Com Express 7 MGMT")
		(sheetfile "com_express_7_mgmt.kicad_sch")
		(attr smd)
		(fp_rect
			(start -0.925 -0.47)
			(end 0.925 0.47)
			(stroke
				(width 0.05)
				(type default)
			)
			(fill no)
			(layer "F.CrtYd")
		)
		(fp_rect
			(start -0.5 -0.25)
			(end 0.5 0.25)
			(stroke
				(width 0.15)
				(type solid)
			)
			(fill no)
			(layer "F.Fab")
		)
		(pad "1" smd roundrect
			(at -0.48 0 270)
			(size 0.59 0.64)
			(layers "F.Cu" "F.Mask" "F.Paste")
			(roundrect_rratio 0.25)
			(net 1 "GND")
			(pintype "passive")
			(teardrops
				(best_length_ratio 0.2)
				(max_length 1)
				(best_width_ratio 0.9)
				(max_width 2)
				(curved_edges yes)
				(filter_ratio 0.9)
				(enabled yes)
				(allow_two_segments yes)
				(prefer_zone_connections yes)
			)
		)
		(pad "2" smd roundrect
			(at 0.48 0 270)
			(size 0.59 0.64)
			(layers "F.Cu" "F.Mask" "F.Paste")
			(roundrect_rratio 0.25)
			(net 382 "Net-(J12D-~{CB_RESET})")
			(pintype "passive")
			(teardrops
				(best_length_ratio 0.2)
				(max_length 1)
				(best_width_ratio 0.9)
				(max_width 2)
				(curved_edges yes)
				(filter_ratio 0.9)
				(enabled yes)
				(allow_two_segments yes)
				(prefer_zone_connections yes)
			)
		)
	)
)
